#ISCELL
  pure_quanta quanta_title_block_c *
  *
#CELL
  pure_quanta socket4677_azif0045p001c01cs *
  page48_i1
